(kicad_pcb
	(version 20241229)
	(generator "pcbnew")
	(generator_version "9.0")
	(general
		(thickness 1.599998)
		(legacy_teardrops no)
	)
	(paper "A4")
	(title_block
		(title "Artix - Datacenter Secure Control Module (DC-SCM)")
		(date "2024-11-06")
		(rev "1.1.3")
		(comment 9 "footprints 468-471 of 544")
	)
	(layers
		(0 "F.Cu" signal)
		(4 "In1.Cu" signal)
		(6 "In2.Cu" signal)
		(8 "In3.Cu" signal)
		(10 "In4.Cu" signal)
		(12 "In5.Cu" signal)
		(14 "In6.Cu" signal)
		(2 "B.Cu" signal)
		(9 "F.Adhes" user "F.Adhesive")
		(11 "B.Adhes" user "B.Adhesive")
		(13 "F.Paste" user)
		(15 "B.Paste" user)
		(5 "F.SilkS" user "F.Silkscreen")
		(7 "B.SilkS" user "B.Silkscreen")
		(1 "F.Mask" user)
		(3 "B.Mask" user)
		(17 "Dwgs.User" user "User.Drawings")
		(19 "Cmts.User" user "User.Comments")
		(21 "Eco1.User" user "User.Eco1")
		(23 "Eco2.User" user "User.Eco2")
		(25 "Edge.Cuts" user)
		(27 "Margin" user)
		(31 "F.CrtYd" user "F.Courtyard")
		(29 "B.CrtYd" user "B.Courtyard")
		(35 "F.Fab" user)
		(33 "B.Fab" user)
	)
	(footprint "antmicro-footprints:SC70-3"
		(layer "B.Cu")
		(at 78.775 87.875 180)
		(property "Reference" "Q2"
			(at 0.675 -1.325 0)
			(layer "B.SilkS")
			(effects
				(font
					(size 0.7 0.7)
					(thickness 0.15)
				)
				(justify left bottom mirror)
			)
		)
		(property "Value" "BSS138PW"
			(at 0 -2.3 0)
			(layer "B.Fab")
			(effects
				(font
					(size 0.7 0.7)
					(thickness 0.15)
				)
				(justify left bottom mirror)
			)
		)
		(property "Datasheet" "https://assets.nexperia.com/documents/data-sheet/BSS138PW.pdf"
			(at 0 0 180)
			(layer "F.Fab")
			(hide yes)
			(effects
				(font
					(size 1.27 1.27)
					(thickness 0.15)
				)
			)
		)
		(property "Description" "Power MOSFET, N Channel, 60 V, 320 mA, 0.9 ohm, SOT-323, Surface Mount"
			(at 0 0 180)
			(layer "F.Fab")
			(hide yes)
			(effects
				(font
					(size 1.27 1.27)
					(thickness 0.15)
				)
			)
		)
		(property "Author" "Antmicro"
			(at 157.55 175.75 0)
			(layer "B.Fab")
			(hide yes)
			(effects
				(font
					(size 1 1)
					(thickness 0.15)
				)
				(justify mirror)
			)
		)
		(property "License" "Apache-2.0"
			(at 157.55 175.75 0)
			(layer "B.Fab")
			(hide yes)
			(effects
				(font
					(size 1 1)
					(thickness 0.15)
				)
				(justify mirror)
			)
		)
		(property "MPN" "BSS138PW"
			(at 157.55 175.75 0)
			(layer "B.Fab")
			(hide yes)
			(effects
				(font
					(size 1 1)
					(thickness 0.15)
				)
				(justify mirror)
			)
		)
		(property "Manufacturer" "Nexperia"
			(at 157.55 175.75 0)
			(layer "B.Fab")
			(hide yes)
			(effects
				(font
					(size 1 1)
					(thickness 0.15)
				)
				(justify mirror)
			)
		)
		(sheetname "/Power supply/")
		(sheetfile "power-supply.kicad_sch")
		(attr smd)
		(fp_line
			(start 0.627 0.6)
			(end 0.627 0.999)
			(stroke
				(width 0.15)
				(type solid)
			)
			(layer "B.SilkS")
		)
		(fp_line
			(start 0.627 -0.6)
			(end 0.627 -1.001)
			(stroke
				(width 0.15)
				(type solid)
			)
			(layer "B.SilkS")
		)
		(fp_line
			(start -0.3 1)
			(end 0.627 0.999)
			(stroke
				(width 0.15)
				(type solid)
			)
			(layer "B.SilkS")
		)
		(fp_line
			(start -0.3 -1)
			(end 0.627 -1.001)
			(stroke
				(width 0.15)
				(type solid)
			)
			(layer "B.SilkS")
		)
		(fp_line
			(start 1.4 0.4)
			(end 1.4 -0.4)
			(stroke
				(width 0.05)
				(type solid)
			)
			(layer "B.CrtYd")
		)
		(fp_line
			(start 1.4 -0.4)
			(end 0.9 -0.4)
			(stroke
				(width 0.05)
				(type solid)
			)
			(layer "B.CrtYd")
		)
		(fp_line
			(start 0.9 1.3)
			(end 0.9 0.4)
			(stroke
				(width 0.05)
				(type solid)
			)
			(layer "B.CrtYd")
		)
		(fp_line
			(start 0.9 0.4)
			(end 1.4 0.4)
			(stroke
				(width 0.05)
				(type solid)
			)
			(layer "B.CrtYd")
		)
		(fp_line
			(start 0.9 -0.4)
			(end 0.9 -1.3)
			(stroke
				(width 0.05)
				(type solid)
			)
			(layer "B.CrtYd")
		)
		(fp_line
			(start 0.9 -1.3)
			(end -0.9 -1.3)
			(stroke
				(width 0.05)
				(type solid)
			)
			(layer "B.CrtYd")
		)
		(fp_line
			(start -0.9 1.3)
			(end 0.9 1.3)
			(stroke
				(width 0.05)
				(type solid)
			)
			(layer "B.CrtYd")
		)
		(fp_line
			(start -0.9 1.3)
			(end -0.9 1)
			(stroke
				(width 0.05)
				(type solid)
			)
			(layer "B.CrtYd")
		)
		(fp_line
			(start -0.9 1)
			(end -1.4 1)
			(stroke
				(width 0.05)
				(type solid)
			)
			(layer "B.CrtYd")
		)
		(fp_line
			(start -0.9 -1)
			(end -1.4 -1)
			(stroke
				(width 0.05)
				(type solid)
			)
			(layer "B.CrtYd")
		)
		(fp_line
			(start -0.9 -1.3)
			(end -0.9 -1)
			(stroke
				(width 0.05)
				(type solid)
			)
			(layer "B.CrtYd")
		)
		(fp_line
			(start -1.4 -1)
			(end -1.4 1)
			(stroke
				(width 0.05)
				(type solid)
			)
			(layer "B.CrtYd")
		)
		(fp_rect
			(start -0.623 0.999)
			(end 0.627 -1.001)
			(stroke
				(width 0.15)
				(type solid)
			)
			(fill no)
			(layer "B.Fab")
		)
		(pad "1" smd rect
			(at -1.051 0.65 90)
			(size 0.6 0.6)
			(layers "B.Cu" "B.Mask" "B.Paste")
			(net 573 "/Power supply/5V0_PG")
			(pinfunction "G")
			(pintype "input")
		)
		(pad "2" smd rect
			(at -1.051 -0.65 90)
			(size 0.6 0.6)
			(layers "B.Cu" "B.Mask" "B.Paste")
			(net 1 "GND")
			(pinfunction "S")
			(pintype "passive")
		)
		(pad "3" smd rect
			(at 1.05 0 90)
			(size 0.6 0.6)
			(layers "B.Cu" "B.Mask" "B.Paste")
			(net 214 "Net-(D5-C)")
			(pinfunction "D")
			(pintype "passive")
		)
	)
	(footprint "antmicro-footprints:SC70-3"
		(layer "B.Cu")
		(at 81.475 96.675 180)
		(property "Reference" "Q3"
			(at 0.775 -1.325 0)
			(layer "B.SilkS")
			(effects
				(font
					(size 0.7 0.7)
					(thickness 0.15)
				)
				(justify left bottom mirror)
			)
		)
		(property "Value" "BSS138PW"
			(at 0 -2.3 0)
			(layer "B.Fab")
			(effects
				(font
					(size 0.7 0.7)
					(thickness 0.15)
				)
				(justify left bottom mirror)
			)
		)
		(property "Datasheet" "https://assets.nexperia.com/documents/data-sheet/BSS138PW.pdf"
			(at 0 0 180)
			(layer "F.Fab")
			(hide yes)
			(effects
				(font
					(size 1.27 1.27)
					(thickness 0.15)
				)
			)
		)
		(property "Description" "Power MOSFET, N Channel, 60 V, 320 mA, 0.9 ohm, SOT-323, Surface Mount"
			(at 0 0 180)
			(layer "F.Fab")
			(hide yes)
			(effects
				(font
					(size 1.27 1.27)
					(thickness 0.15)
				)
			)
		)
		(property "Author" "Antmicro"
			(at 162.95 193.35 0)
			(layer "B.Fab")
			(hide yes)
			(effects
				(font
					(size 1 1)
					(thickness 0.15)
				)
				(justify mirror)
			)
		)
		(property "License" "Apache-2.0"
			(at 162.95 193.35 0)
			(layer "B.Fab")
			(hide yes)
			(effects
				(font
					(size 1 1)
					(thickness 0.15)
				)
				(justify mirror)
			)
		)
		(property "MPN" "BSS138PW"
			(at 162.95 193.35 0)
			(layer "B.Fab")
			(hide yes)
			(effects
				(font
					(size 1 1)
					(thickness 0.15)
				)
				(justify mirror)
			)
		)
		(property "Manufacturer" "Nexperia"
			(at 162.95 193.35 0)
			(layer "B.Fab")
			(hide yes)
			(effects
				(font
					(size 1 1)
					(thickness 0.15)
				)
				(justify mirror)
			)
		)
		(sheetname "/Power supply/")
		(sheetfile "power-supply.kicad_sch")
		(attr smd)
		(fp_line
			(start 0.627 0.6)
			(end 0.627 0.999)
			(stroke
				(width 0.15)
				(type solid)
			)
			(layer "B.SilkS")
		)
		(fp_line
			(start 0.627 -0.6)
			(end 0.627 -1.001)
			(stroke
				(width 0.15)
				(type solid)
			)
			(layer "B.SilkS")
		)
		(fp_line
			(start -0.3 1)
			(end 0.627 0.999)
			(stroke
				(width 0.15)
				(type solid)
			)
			(layer "B.SilkS")
		)
		(fp_line
			(start -0.3 -1)
			(end 0.627 -1.001)
			(stroke
				(width 0.15)
				(type solid)
			)
			(layer "B.SilkS")
		)
		(fp_line
			(start 1.4 0.4)
			(end 1.4 -0.4)
			(stroke
				(width 0.05)
				(type solid)
			)
			(layer "B.CrtYd")
		)
		(fp_line
			(start 1.4 -0.4)
			(end 0.9 -0.4)
			(stroke
				(width 0.05)
				(type solid)
			)
			(layer "B.CrtYd")
		)
		(fp_line
			(start 0.9 1.3)
			(end 0.9 0.4)
			(stroke
				(width 0.05)
				(type solid)
			)
			(layer "B.CrtYd")
		)
		(fp_line
			(start 0.9 0.4)
			(end 1.4 0.4)
			(stroke
				(width 0.05)
				(type solid)
			)
			(layer "B.CrtYd")
		)
		(fp_line
			(start 0.9 -0.4)
			(end 0.9 -1.3)
			(stroke
				(width 0.05)
				(type solid)
			)
			(layer "B.CrtYd")
		)
		(fp_line
			(start 0.9 -1.3)
			(end -0.9 -1.3)
			(stroke
				(width 0.05)
				(type solid)
			)
			(layer "B.CrtYd")
		)
		(fp_line
			(start -0.9 1.3)
			(end 0.9 1.3)
			(stroke
				(width 0.05)
				(type solid)
			)
			(layer "B.CrtYd")
		)
		(fp_line
			(start -0.9 1.3)
			(end -0.9 1)
			(stroke
				(width 0.05)
				(type solid)
			)
			(layer "B.CrtYd")
		)
		(fp_line
			(start -0.9 1)
			(end -1.4 1)
			(stroke
				(width 0.05)
				(type solid)
			)
			(layer "B.CrtYd")
		)
		(fp_line
			(start -0.9 -1)
			(end -1.4 -1)
			(stroke
				(width 0.05)
				(type solid)
			)
			(layer "B.CrtYd")
		)
		(fp_line
			(start -0.9 -1.3)
			(end -0.9 -1)
			(stroke
				(width 0.05)
				(type solid)
			)
			(layer "B.CrtYd")
		)
		(fp_line
			(start -1.4 -1)
			(end -1.4 1)
			(stroke
				(width 0.05)
				(type solid)
			)
			(layer "B.CrtYd")
		)
		(fp_rect
			(start -0.623 0.999)
			(end 0.627 -1.001)
			(stroke
				(width 0.15)
				(type solid)
			)
			(fill no)
			(layer "B.Fab")
		)
		(pad "1" smd rect
			(at -1.051 0.65 90)
			(size 0.6 0.6)
			(layers "B.Cu" "B.Mask" "B.Paste")
			(net 292 "/Power supply/1V8_PG")
			(pinfunction "G")
			(pintype "input")
		)
		(pad "2" smd rect
			(at -1.051 -0.65 90)
			(size 0.6 0.6)
			(layers "B.Cu" "B.Mask" "B.Paste")
			(net 1 "GND")
			(pinfunction "S")
			(pintype "passive")
		)
		(pad "3" smd rect
			(at 1.05 0 90)
			(size 0.6 0.6)
			(layers "B.Cu" "B.Mask" "B.Paste")
			(net 216 "Net-(D6-C)")
			(pinfunction "D")
			(pintype "passive")
		)
	)
	(footprint "antmicro-footprints:SC70-3"
		(layer "B.Cu")
		(at 81.575 89.275 180)
		(property "Reference" "Q4"
			(at 0.775 -1.225 0)
			(layer "B.SilkS")
			(effects
				(font
					(size 0.7 0.7)
					(thickness 0.15)
				)
				(justify left bottom mirror)
			)
		)
		(property "Value" "BSS138PW"
			(at 0 -2.3 0)
			(layer "B.Fab")
			(effects
				(font
					(size 0.7 0.7)
					(thickness 0.15)
				)
				(justify left bottom mirror)
			)
		)
		(property "Datasheet" "https://assets.nexperia.com/documents/data-sheet/BSS138PW.pdf"
			(at 0 0 180)
			(layer "F.Fab")
			(hide yes)
			(effects
				(font
					(size 1.27 1.27)
					(thickness 0.15)
				)
			)
		)
		(property "Description" "Power MOSFET, N Channel, 60 V, 320 mA, 0.9 ohm, SOT-323, Surface Mount"
			(at 0 0 180)
			(layer "F.Fab")
			(hide yes)
			(effects
				(font
					(size 1.27 1.27)
					(thickness 0.15)
				)
			)
		)
		(property "Author" "Antmicro"
			(at 163.15 178.55 0)
			(layer "B.Fab")
			(hide yes)
			(effects
				(font
					(size 1 1)
					(thickness 0.15)
				)
				(justify mirror)
			)
		)
		(property "License" "Apache-2.0"
			(at 163.15 178.55 0)
			(layer "B.Fab")
			(hide yes)
			(effects
				(font
					(size 1 1)
					(thickness 0.15)
				)
				(justify mirror)
			)
		)
		(property "MPN" "BSS138PW"
			(at 163.15 178.55 0)
			(layer "B.Fab")
			(hide yes)
			(effects
				(font
					(size 1 1)
					(thickness 0.15)
				)
				(justify mirror)
			)
		)
		(property "Manufacturer" "Nexperia"
			(at 163.15 178.55 0)
			(layer "B.Fab")
			(hide yes)
			(effects
				(font
					(size 1 1)
					(thickness 0.15)
				)
				(justify mirror)
			)
		)
		(sheetname "/Power supply/")
		(sheetfile "power-supply.kicad_sch")
		(attr smd)
		(fp_line
			(start 0.627 0.6)
			(end 0.627 0.999)
			(stroke
				(width 0.15)
				(type solid)
			)
			(layer "B.SilkS")
		)
		(fp_line
			(start 0.627 -0.6)
			(end 0.627 -1.001)
			(stroke
				(width 0.15)
				(type solid)
			)
			(layer "B.SilkS")
		)
		(fp_line
			(start -0.3 1)
			(end 0.627 0.999)
			(stroke
				(width 0.15)
				(type solid)
			)
			(layer "B.SilkS")
		)
		(fp_line
			(start -0.3 -1)
			(end 0.627 -1.001)
			(stroke
				(width 0.15)
				(type solid)
			)
			(layer "B.SilkS")
		)
		(fp_line
			(start 1.4 0.4)
			(end 1.4 -0.4)
			(stroke
				(width 0.05)
				(type solid)
			)
			(layer "B.CrtYd")
		)
		(fp_line
			(start 1.4 -0.4)
			(end 0.9 -0.4)
			(stroke
				(width 0.05)
				(type solid)
			)
			(layer "B.CrtYd")
		)
		(fp_line
			(start 0.9 1.3)
			(end 0.9 0.4)
			(stroke
				(width 0.05)
				(type solid)
			)
			(layer "B.CrtYd")
		)
		(fp_line
			(start 0.9 0.4)
			(end 1.4 0.4)
			(stroke
				(width 0.05)
				(type solid)
			)
			(layer "B.CrtYd")
		)
		(fp_line
			(start 0.9 -0.4)
			(end 0.9 -1.3)
			(stroke
				(width 0.05)
				(type solid)
			)
			(layer "B.CrtYd")
		)
		(fp_line
			(start 0.9 -1.3)
			(end -0.9 -1.3)
			(stroke
				(width 0.05)
				(type solid)
			)
			(layer "B.CrtYd")
		)
		(fp_line
			(start -0.9 1.3)
			(end 0.9 1.3)
			(stroke
				(width 0.05)
				(type solid)
			)
			(layer "B.CrtYd")
		)
		(fp_line
			(start -0.9 1.3)
			(end -0.9 1)
			(stroke
				(width 0.05)
				(type solid)
			)
			(layer "B.CrtYd")
		)
		(fp_line
			(start -0.9 1)
			(end -1.4 1)
			(stroke
				(width 0.05)
				(type solid)
			)
			(layer "B.CrtYd")
		)
		(fp_line
			(start -0.9 -1)
			(end -1.4 -1)
			(stroke
				(width 0.05)
				(type solid)
			)
			(layer "B.CrtYd")
		)
		(fp_line
			(start -0.9 -1.3)
			(end -0.9 -1)
			(stroke
				(width 0.05)
				(type solid)
			)
			(layer "B.CrtYd")
		)
		(fp_line
			(start -1.4 -1)
			(end -1.4 1)
			(stroke
				(width 0.05)
				(type solid)
			)
			(layer "B.CrtYd")
		)
		(fp_rect
			(start -0.623 0.999)
			(end 0.627 -1.001)
			(stroke
				(width 0.15)
				(type solid)
			)
			(fill no)
			(layer "B.Fab")
		)
		(pad "1" smd rect
			(at -1.051 0.65 90)
			(size 0.6 0.6)
			(layers "B.Cu" "B.Mask" "B.Paste")
			(net 293 "/Power supply/1V35_PG")
			(pinfunction "G")
			(pintype "input")
		)
		(pad "2" smd rect
			(at -1.051 -0.65 90)
			(size 0.6 0.6)
			(layers "B.Cu" "B.Mask" "B.Paste")
			(net 1 "GND")
			(pinfunction "S")
			(pintype "passive")
		)
		(pad "3" smd rect
			(at 1.05 0 90)
			(size 0.6 0.6)
			(layers "B.Cu" "B.Mask" "B.Paste")
			(net 218 "Net-(D7-C)")
			(pinfunction "D")
			(pintype "passive")
		)
	)
	(footprint "antmicro-footprints:SC70-3"
		(layer "B.Cu")
		(at 81.475 103.975 180)
		(property "Reference" "Q5"
			(at 0.775 -1.325 0)
			(layer "B.SilkS")
			(effects
				(font
					(size 0.7 0.7)
					(thickness 0.15)
				)
				(justify left bottom mirror)
			)
		)
		(property "Value" "BSS138PW"
			(at 0 -2.3 0)
			(layer "B.Fab")
			(effects
				(font
					(size 0.7 0.7)
					(thickness 0.15)
				)
				(justify left bottom mirror)
			)
		)
		(property "Datasheet" "https://assets.nexperia.com/documents/data-sheet/BSS138PW.pdf"
			(at 0 0 180)
			(layer "F.Fab")
			(hide yes)
			(effects
				(font
					(size 1.27 1.27)
					(thickness 0.15)
				)
			)
		)
		(property "Description" "Power MOSFET, N Channel, 60 V, 320 mA, 0.9 ohm, SOT-323, Surface Mount"
			(at 0 0 180)
			(layer "F.Fab")
			(hide yes)
			(effects
				(font
					(size 1.27 1.27)
					(thickness 0.15)
				)
			)
		)
		(property "Author" "Antmicro"
			(at 162.95 207.95 0)
			(layer "B.Fab")
			(hide yes)
			(effects
				(font
					(size 1 1)
					(thickness 0.15)
				)
				(justify mirror)
			)
		)
		(property "License" "Apache-2.0"
			(at 162.95 207.95 0)
			(layer "B.Fab")
			(hide yes)
			(effects
				(font
					(size 1 1)
					(thickness 0.15)
				)
				(justify mirror)
			)
		)
		(property "MPN" "BSS138PW"
			(at 162.95 207.95 0)
			(layer "B.Fab")
			(hide yes)
			(effects
				(font
					(size 1 1)
					(thickness 0.15)
				)
				(justify mirror)
			)
		)
		(property "Manufacturer" "Nexperia"
			(at 162.95 207.95 0)
			(layer "B.Fab")
			(hide yes)
			(effects
				(font
					(size 1 1)
					(thickness 0.15)
				)
				(justify mirror)
			)
		)
		(sheetname "/Power supply/")
		(sheetfile "power-supply.kicad_sch")
		(attr smd)
		(fp_line
			(start 0.627 0.6)
			(end 0.627 0.999)
			(stroke
				(width 0.15)
				(type solid)
			)
			(layer "B.SilkS")
		)
		(fp_line
			(start 0.627 -0.6)
			(end 0.627 -1.001)
			(stroke
				(width 0.15)
				(type solid)
			)
			(layer "B.SilkS")
		)
		(fp_line
			(start -0.3 1)
			(end 0.627 0.999)
			(stroke
				(width 0.15)
				(type solid)
			)
			(layer "B.SilkS")
		)
		(fp_line
			(start -0.3 -1)
			(end 0.627 -1.001)
			(stroke
				(width 0.15)
				(type solid)
			)
			(layer "B.SilkS")
		)
		(fp_line
			(start 1.4 0.4)
			(end 1.4 -0.4)
			(stroke
				(width 0.05)
				(type solid)
			)
			(layer "B.CrtYd")
		)
		(fp_line
			(start 1.4 -0.4)
			(end 0.9 -0.4)
			(stroke
				(width 0.05)
				(type solid)
			)
			(layer "B.CrtYd")
		)
		(fp_line
			(start 0.9 1.3)
			(end 0.9 0.4)
			(stroke
				(width 0.05)
				(type solid)
			)
			(layer "B.CrtYd")
		)
		(fp_line
			(start 0.9 0.4)
			(end 1.4 0.4)
			(stroke
				(width 0.05)
				(type solid)
			)
			(layer "B.CrtYd")
		)
		(fp_line
			(start 0.9 -0.4)
			(end 0.9 -1.3)
			(stroke
				(width 0.05)
				(type solid)
			)
			(layer "B.CrtYd")
		)
		(fp_line
			(start 0.9 -1.3)
			(end -0.9 -1.3)
			(stroke
				(width 0.05)
				(type solid)
			)
			(layer "B.CrtYd")
		)
		(fp_line
			(start -0.9 1.3)
			(end 0.9 1.3)
			(stroke
				(width 0.05)
				(type solid)
			)
			(layer "B.CrtYd")
		)
		(fp_line
			(start -0.9 1.3)
			(end -0.9 1)
			(stroke
				(width 0.05)
				(type solid)
			)
			(layer "B.CrtYd")
		)
		(fp_line
			(start -0.9 1)
			(end -1.4 1)
			(stroke
				(width 0.05)
				(type solid)
			)
			(layer "B.CrtYd")
		)
		(fp_line
			(start -0.9 -1)
			(end -1.4 -1)
			(stroke
				(width 0.05)
				(type solid)
			)
			(layer "B.CrtYd")
		)
		(fp_line
			(start -0.9 -1.3)
			(end -0.9 -1)
			(stroke
				(width 0.05)
				(type solid)
			)
			(layer "B.CrtYd")
		)
		(fp_line
			(start -1.4 -1)
			(end -1.4 1)
			(stroke
				(width 0.05)
				(type solid)
			)
			(layer "B.CrtYd")
		)
		(fp_rect
			(start -0.623 0.999)
			(end 0.627 -1.001)
			(stroke
				(width 0.15)
				(type solid)
			)
			(fill no)
			(layer "B.Fab")
		)
		(pad "1" smd rect
			(at -1.051 0.65 90)
			(size 0.6 0.6)
			(layers "B.Cu" "B.Mask" "B.Paste")
			(net 294 "/Power supply/2V5_PG")
			(pinfunction "G")
			(pintype "input")
		)
		(pad "2" smd rect
			(at -1.051 -0.65 90)
			(size 0.6 0.6)
			(layers "B.Cu" "B.Mask" "B.Paste")
			(net 1 "GND")
			(pinfunction "S")
			(pintype "passive")
		)
		(pad "3" smd rect
			(at 1.05 0 90)
			(size 0.6 0.6)
			(layers "B.Cu" "B.Mask" "B.Paste")
			(net 223 "Net-(D8-C)")
			(pinfunction "D")
			(pintype "passive")
		)
	)
)
